(kicad_pcb
	(version 20241229)
	(generator "pcbnew")
	(generator_version "9.0")
	(general
		(thickness 1.6642)
		(legacy_teardrops no)
	)
	(paper "A3")
	(title_block
		(title "PolarFire SoM")
		(date "2025-07-22")
		(rev "1.1.4")
		(company "Antmicro Ltd")
		(comment 1 "www.antmicro.com")
		(comment 9 "footprints 347-350 of 470")
	)
	(layers
		(0 "F.Cu" mixed)
		(4 "In1.Cu" power)
		(6 "In2.Cu" signal)
		(8 "In3.Cu" power)
		(10 "In4.Cu" signal)
		(12 "In5.Cu" power)
		(14 "In6.Cu" power)
		(16 "In7.Cu" signal)
		(18 "In8.Cu" power)
		(20 "In9.Cu" signal)
		(22 "In10.Cu" power)
		(24 "In11.Cu" signal)
		(26 "In12.Cu" signal)
		(2 "B.Cu" mixed)
		(9 "F.Adhes" user "F.Adhesive")
		(11 "B.Adhes" user "B.Adhesive")
		(13 "F.Paste" user)
		(15 "B.Paste" user)
		(5 "F.SilkS" user "F.Silkscreen")
		(7 "B.SilkS" user "B.Silkscreen")
		(1 "F.Mask" user)
		(3 "B.Mask" user)
		(17 "Dwgs.User" user "User.Drawings")
		(19 "Cmts.User" user "User.Comments")
		(21 "Eco1.User" user "User.Eco1")
		(23 "Eco2.User" user "User.Eco2")
		(25 "Edge.Cuts" user)
		(27 "Margin" user)
		(31 "F.CrtYd" user "F.Courtyard")
		(29 "B.CrtYd" user "B.Courtyard")
		(35 "F.Fab" user)
		(33 "B.Fab" user)
	)
	(footprint "antmicro-footprints:C_0402_1005Metric"
		(layer "B.Cu")
		(at 181.1 144.0125)
		(descr "Capacitor SMD 0402")
		(tags "capacitor SMD 0402")
		(property "Reference" "C112"
			(at 0.2 1.1175 315)
			(layer "B.SilkS")
			(effects
				(font
					(size 0.7 0.7)
					(thickness 0.15)
				)
				(justify right bottom mirror)
			)
		)
		(property "Value" "C_10u_10V_0402"
			(at -1.022927 -2.155213 0)
			(layer "B.Fab")
			(hide yes)
			(effects
				(font
					(size 0.7 0.7)
					(thickness 0.15)
				)
				(justify right bottom mirror)
			)
		)
		(property "Datasheet" "https://www.murata.com/products/productdetail?partno=GRM155R61A106ME11%23"
			(at 0 0 0)
			(layer "F.Fab")
			(hide yes)
			(effects
				(font
					(size 1.27 1.27)
					(thickness 0.15)
				)
			)
		)
		(property "Description" "Multilayer Ceramic Capacitors MLCC - SMD/SMT 10 uF 10 VDC 20% 0402 X5R"
			(at 0 0 0)
			(layer "F.Fab")
			(hide yes)
			(effects
				(font
					(size 1.27 1.27)
					(thickness 0.15)
				)
			)
		)
		(property "Author" "Antmicro"
			(at 0 0 0)
			(layer "B.Fab")
			(hide yes)
			(effects
				(font
					(size 1 1)
					(thickness 0.15)
				)
				(justify mirror)
			)
		)
		(property "Dielectric" "X5R"
			(at 0 0 0)
			(layer "B.Fab")
			(hide yes)
			(effects
				(font
					(size 1 1)
					(thickness 0.15)
				)
				(justify mirror)
			)
		)
		(property "License" "Apache-2.0"
			(at 0 0 0)
			(layer "B.Fab")
			(hide yes)
			(effects
				(font
					(size 1 1)
					(thickness 0.15)
				)
				(justify mirror)
			)
		)
		(property "MPN" "GRM155R61A106ME11D"
			(at 0 0 0)
			(layer "B.Fab")
			(hide yes)
			(effects
				(font
					(size 1 1)
					(thickness 0.15)
				)
				(justify mirror)
			)
		)
		(property "Manufacturer" "Murata"
			(at 0 0 0)
			(layer "B.Fab")
			(hide yes)
			(effects
				(font
					(size 1 1)
					(thickness 0.15)
				)
				(justify mirror)
			)
		)
		(property "Public" ""
			(at 0 0 0)
			(layer "B.Fab")
			(hide yes)
			(effects
				(font
					(size 1 1)
					(thickness 0.15)
				)
				(justify mirror)
			)
		)
		(property "Val" "10u"
			(at 0 0 0)
			(layer "B.Fab")
			(hide yes)
			(effects
				(font
					(size 1 1)
					(thickness 0.15)
				)
				(justify mirror)
			)
		)
		(property "Voltage" "10V"
			(at 0 0 0)
			(layer "B.Fab")
			(hide yes)
			(effects
				(font
					(size 1 1)
					(thickness 0.15)
				)
				(justify mirror)
			)
		)
		(sheetname "/Supply/")
		(sheetfile "supply.kicad_sch")
		(attr smd)
		(fp_rect
			(start -0.925 0.47)
			(end 0.925 -0.47)
			(stroke
				(width 0.05)
				(type default)
			)
			(fill no)
			(layer "B.CrtYd")
		)
		(fp_line
			(start -0.494 -0.248)
			(end -0.494 0.25)
			(stroke
				(width 0.15)
				(type solid)
			)
			(layer "B.Fab")
		)
		(fp_line
			(start -0.494 0.25)
			(end 0.504 0.25)
			(stroke
				(width 0.15)
				(type solid)
			)
			(layer "B.Fab")
		)
		(fp_line
			(start 0.504 -0.248)
			(end -0.494 -0.248)
			(stroke
				(width 0.15)
				(type solid)
			)
			(layer "B.Fab")
		)
		(fp_line
			(start 0.504 0.25)
			(end 0.504 -0.248)
			(stroke
				(width 0.15)
				(type solid)
			)
			(layer "B.Fab")
		)
		(fp_text user "Author: Antmicro"
			(at -0.939 -3.399 180)
			(layer "B.Fab")
			(effects
				(font
					(size 0.7 0.7)
					(thickness 0.15)
				)
				(justify left bottom mirror)
			)
		)
		(fp_text user "License: Apache-2.0"
			(at -0.939 -5.799 180)
			(layer "B.Fab")
			(effects
				(font
					(size 0.7 0.7)
					(thickness 0.15)
				)
				(justify left bottom mirror)
			)
		)
		(fp_text user "${REFERENCE}"
			(at -0.939 -4.599 180)
			(layer "B.Fab")
			(effects
				(font
					(size 0.7 0.7)
					(thickness 0.15)
				)
				(justify left bottom mirror)
			)
		)
		(pad "1" smd roundrect
			(at -0.48 0)
			(size 0.59 0.64)
			(layers "B.Cu" "B.Mask" "B.Paste")
			(roundrect_rratio 0.25)
			(net 417 "GND")
			(pintype "passive")
		)
		(pad "2" smd roundrect
			(at 0.48 0)
			(size 0.59 0.64)
			(layers "B.Cu" "B.Mask" "B.Paste")
			(roundrect_rratio 0.25)
			(net 634 "Net-(U7-OUT5)")
			(pintype "passive")
		)
	)
	(footprint "antmicro-footprints:C_0402_1005Metric"
		(layer "B.Cu")
		(at 221.9325 147.295 90)
		(descr "Capacitor SMD 0402")
		(tags "capacitor SMD 0402")
		(property "Reference" "C228"
			(at -3.725 0.8975 90)
			(layer "B.SilkS")
			(effects
				(font
					(size 0.7 0.7)
					(thickness 0.15)
				)
				(justify right bottom mirror)
			)
		)
		(property "Value" "C_100n_0402"
			(at -1.022927 -2.155213 90)
			(layer "B.Fab")
			(hide yes)
			(effects
				(font
					(size 0.7 0.7)
					(thickness 0.15)
				)
				(justify right bottom mirror)
			)
		)
		(property "Datasheet" "https://www.murata.com/products/productdetail?partno=GRM155R61H104KE14%23"
			(at 0 0 90)
			(layer "F.Fab")
			(hide yes)
			(effects
				(font
					(size 1.27 1.27)
					(thickness 0.15)
				)
			)
		)
		(property "Description" "SMD Multilayer Ceramic Capacitor, 0.1 µF, 50 V, 0402 [1005 Metric], ± 10%, X5R, GRM Series"
			(at 0 0 90)
			(layer "F.Fab")
			(hide yes)
			(effects
				(font
					(size 1.27 1.27)
					(thickness 0.15)
				)
			)
		)
		(property "Author" "Antmicro"
			(at 369.2275 -74.6375 0)
			(layer "B.Fab")
			(hide yes)
			(effects
				(font
					(size 1 1)
					(thickness 0.15)
				)
				(justify mirror)
			)
		)
		(property "Dielectric" "X5R"
			(at 369.2275 -74.6375 0)
			(layer "B.Fab")
			(hide yes)
			(effects
				(font
					(size 1 1)
					(thickness 0.15)
				)
				(justify mirror)
			)
		)
		(property "License" "Apache-2.0"
			(at 369.2275 -74.6375 0)
			(layer "B.Fab")
			(hide yes)
			(effects
				(font
					(size 1 1)
					(thickness 0.15)
				)
				(justify mirror)
			)
		)
		(property "MPN" "GRM155R61H104KE14D"
			(at 369.2275 -74.6375 0)
			(layer "B.Fab")
			(hide yes)
			(effects
				(font
					(size 1 1)
					(thickness 0.15)
				)
				(justify mirror)
			)
		)
		(property "Manufacturer" "Murata"
			(at 369.2275 -74.6375 0)
			(layer "B.Fab")
			(hide yes)
			(effects
				(font
					(size 1 1)
					(thickness 0.15)
				)
				(justify mirror)
			)
		)
		(property "Public" ""
			(at 369.2275 -74.6375 0)
			(layer "B.Fab")
			(hide yes)
			(effects
				(font
					(size 1 1)
					(thickness 0.15)
				)
				(justify mirror)
			)
		)
		(property "Val" "100n"
			(at 369.2275 -74.6375 0)
			(layer "B.Fab")
			(hide yes)
			(effects
				(font
					(size 1 1)
					(thickness 0.15)
				)
				(justify mirror)
			)
		)
		(property "Voltage" "50V"
			(at 369.2275 -74.6375 0)
			(layer "B.Fab")
			(hide yes)
			(effects
				(font
					(size 1 1)
					(thickness 0.15)
				)
				(justify mirror)
			)
		)
		(sheetname "/WiFi_Bluetooth/")
		(sheetfile "wifi_bt.kicad_sch")
		(attr smd)
		(fp_rect
			(start -0.925 0.47)
			(end 0.925 -0.47)
			(stroke
				(width 0.05)
				(type default)
			)
			(fill no)
			(layer "B.CrtYd")
		)
		(fp_line
			(start 0.504 -0.248)
			(end -0.494 -0.248)
			(stroke
				(width 0.15)
				(type solid)
			)
			(layer "B.Fab")
		)
		(fp_line
			(start -0.494 -0.248)
			(end -0.494 0.25)
			(stroke
				(width 0.15)
				(type solid)
			)
			(layer "B.Fab")
		)
		(fp_line
			(start 0.504 0.25)
			(end 0.504 -0.248)
			(stroke
				(width 0.15)
				(type solid)
			)
			(layer "B.Fab")
		)
		(fp_line
			(start -0.494 0.25)
			(end 0.504 0.25)
			(stroke
				(width 0.15)
				(type solid)
			)
			(layer "B.Fab")
		)
		(fp_text user "License: Apache-2.0"
			(at -0.939 -5.799 270)
			(layer "B.Fab")
			(effects
				(font
					(size 0.7 0.7)
					(thickness 0.15)
				)
				(justify left bottom mirror)
			)
		)
		(fp_text user "${REFERENCE}"
			(at -0.939 -4.599 270)
			(layer "B.Fab")
			(effects
				(font
					(size 0.7 0.7)
					(thickness 0.15)
				)
				(justify left bottom mirror)
			)
		)
		(fp_text user "Author: Antmicro"
			(at -0.939 -3.399 270)
			(layer "B.Fab")
			(effects
				(font
					(size 0.7 0.7)
					(thickness 0.15)
				)
				(justify left bottom mirror)
			)
		)
		(pad "1" smd roundrect
			(at -0.48 0 90)
			(size 0.59 0.64)
			(layers "B.Cu" "B.Mask" "B.Paste")
			(roundrect_rratio 0.25)
			(net 417 "GND")
			(pintype "passive")
		)
		(pad "2" smd roundrect
			(at 0.48 0 90)
			(size 0.59 0.64)
			(layers "B.Cu" "B.Mask" "B.Paste")
			(roundrect_rratio 0.25)
			(net 171 "WL_REG_ON")
			(pintype "passive")
		)
	)
	(footprint "antmicro-footprints:C_0402_1005Metric"
		(layer "B.Cu")
		(at 198.91 128.75 -90)
		(descr "Capacitor SMD 0402")
		(tags "capacitor SMD 0402")
		(property "Reference" "C26"
			(at -1.05 0.41 90)
			(layer "B.SilkS")
			(effects
				(font
					(size 0.7 0.7)
					(thickness 0.15)
				)
				(justify left bottom mirror)
			)
		)
		(property "Value" "C_1n_0402"
			(at -1.022927 -2.155213 90)
			(layer "B.Fab")
			(hide yes)
			(effects
				(font
					(size 0.7 0.7)
					(thickness 0.15)
				)
				(justify left bottom mirror)
			)
		)
		(property "Datasheet" "https://www.murata.com/products/productdetail?partno=GRM1555C1H102JA01%23"
			(at 0 0 270)
			(layer "F.Fab")
			(hide yes)
			(effects
				(font
					(size 1.27 1.27)
					(thickness 0.15)
				)
			)
		)
		(property "Description" "SMD Multilayer Ceramic Capacitor, 1000 pF, 50 V, 0402 [1005 Metric], ± 5%, C0G / NP0, GRM Series"
			(at 0 0 270)
			(layer "F.Fab")
			(hide yes)
			(effects
				(font
					(size 1.27 1.27)
					(thickness 0.15)
				)
			)
		)
		(property "Author" "Antmicro"
			(at 70.16 327.66 0)
			(layer "B.Fab")
			(hide yes)
			(effects
				(font
					(size 1 1)
					(thickness 0.15)
				)
				(justify mirror)
			)
		)
		(property "Dielectric" "C0G"
			(at 70.16 327.66 0)
			(layer "B.Fab")
			(hide yes)
			(effects
				(font
					(size 1 1)
					(thickness 0.15)
				)
				(justify mirror)
			)
		)
		(property "License" "Apache-2.0"
			(at 70.16 327.66 0)
			(layer "B.Fab")
			(hide yes)
			(effects
				(font
					(size 1 1)
					(thickness 0.15)
				)
				(justify mirror)
			)
		)
		(property "MPN" "GRM1555C1H102JA01D"
			(at 70.16 327.66 0)
			(layer "B.Fab")
			(hide yes)
			(effects
				(font
					(size 1 1)
					(thickness 0.15)
				)
				(justify mirror)
			)
		)
		(property "Manufacturer" "Murata"
			(at 70.16 327.66 0)
			(layer "B.Fab")
			(hide yes)
			(effects
				(font
					(size 1 1)
					(thickness 0.15)
				)
				(justify mirror)
			)
		)
		(property "Public" ""
			(at 70.16 327.66 0)
			(layer "B.Fab")
			(hide yes)
			(effects
				(font
					(size 1 1)
					(thickness 0.15)
				)
				(justify mirror)
			)
		)
		(property "Val" "1n"
			(at 70.16 327.66 0)
			(layer "B.Fab")
			(hide yes)
			(effects
				(font
					(size 1 1)
					(thickness 0.15)
				)
				(justify mirror)
			)
		)
		(property "Voltage" "50V"
			(at 70.16 327.66 0)
			(layer "B.Fab")
			(hide yes)
			(effects
				(font
					(size 1 1)
					(thickness 0.15)
				)
				(justify mirror)
			)
		)
		(sheetname "/FPGA Supply/")
		(sheetfile "fpga-supply.kicad_sch")
		(attr smd)
		(fp_rect
			(start -0.925 0.47)
			(end 0.925 -0.47)
			(stroke
				(width 0.05)
				(type default)
			)
			(fill no)
			(layer "B.CrtYd")
		)
		(fp_line
			(start -0.494 0.25)
			(end 0.504 0.25)
			(stroke
				(width 0.15)
				(type solid)
			)
			(layer "B.Fab")
		)
		(fp_line
			(start 0.504 0.25)
			(end 0.504 -0.248)
			(stroke
				(width 0.15)
				(type solid)
			)
			(layer "B.Fab")
		)
		(fp_line
			(start -0.494 -0.248)
			(end -0.494 0.25)
			(stroke
				(width 0.15)
				(type solid)
			)
			(layer "B.Fab")
		)
		(fp_line
			(start 0.504 -0.248)
			(end -0.494 -0.248)
			(stroke
				(width 0.15)
				(type solid)
			)
			(layer "B.Fab")
		)
		(fp_text user "License: Apache-2.0"
			(at -0.939 -5.799 90)
			(layer "B.Fab")
			(effects
				(font
					(size 0.7 0.7)
					(thickness 0.15)
				)
				(justify left bottom mirror)
			)
		)
		(fp_text user "Author: Antmicro"
			(at -0.939 -3.399 90)
			(layer "B.Fab")
			(effects
				(font
					(size 0.7 0.7)
					(thickness 0.15)
				)
				(justify left bottom mirror)
			)
		)
		(fp_text user "${REFERENCE}"
			(at -0.939 -4.599 90)
			(layer "B.Fab")
			(effects
				(font
					(size 0.7 0.7)
					(thickness 0.15)
				)
				(justify left bottom mirror)
			)
		)
		(pad "1" smd roundrect
			(at -0.48 0 270)
			(size 0.59 0.64)
			(layers "B.Cu" "B.Mask" "B.Paste")
			(roundrect_rratio 0.25)
			(net 417 "GND")
			(pintype "passive")
		)
		(pad "2" smd roundrect
			(at 0.48 0 270)
			(size 0.59 0.64)
			(layers "B.Cu" "B.Mask" "B.Paste")
			(roundrect_rratio 0.25)
			(net 418 "+2V5")
			(pintype "passive")
		)
	)
	(footprint "antmicro-footprints:C_0402_1005Metric"
		(layer "B.Cu")
		(at 214.915 149.55 -90)
		(descr "Capacitor SMD 0402")
		(tags "capacitor SMD 0402")
		(property "Reference" "C292"
			(at 0.86 -0.375 90)
			(layer "B.SilkS")
			(effects
				(font
					(size 0.7 0.7)
					(thickness 0.15)
				)
				(justify left bottom mirror)
			)
		)
		(property "Value" "C_1u_0402"
			(at -1.022927 -2.155213 90)
			(layer "B.Fab")
			(hide yes)
			(effects
				(font
					(size 0.7 0.7)
					(thickness 0.15)
				)
				(justify left bottom mirror)
			)
		)
		(property "Datasheet" "https://product.tdk.com/en/search/capacitor/ceramic/mlcc/info?part_no=C1005X6S1A105K050BC"
			(at 0 0 270)
			(layer "F.Fab")
			(hide yes)
			(effects
				(font
					(size 1.27 1.27)
					(thickness 0.15)
				)
			)
		)
		(property "Description" "SMD Multilayer Ceramic Capacitor, 1 µF, 10 V, 0402 [1005 Metric], ± 10%, X6S, C"
			(at 0 0 270)
			(layer "F.Fab")
			(hide yes)
			(effects
				(font
					(size 1.27 1.27)
					(thickness 0.15)
				)
			)
		)
		(property "Author" "Antmicro"
			(at 65.365 364.465 0)
			(layer "B.Fab")
			(hide yes)
			(effects
				(font
					(size 1 1)
					(thickness 0.15)
				)
				(justify mirror)
			)
		)
		(property "Dielectric" ""
			(at 65.365 364.465 0)
			(layer "B.Fab")
			(hide yes)
			(effects
				(font
					(size 1 1)
					(thickness 0.15)
				)
				(justify mirror)
			)
		)
		(property "License" "Apache-2.0"
			(at 65.365 364.465 0)
			(layer "B.Fab")
			(hide yes)
			(effects
				(font
					(size 1 1)
					(thickness 0.15)
				)
				(justify mirror)
			)
		)
		(property "MPN" "C1005X6S1A105K050BC"
			(at 65.365 364.465 0)
			(layer "B.Fab")
			(hide yes)
			(effects
				(font
					(size 1 1)
					(thickness 0.15)
				)
				(justify mirror)
			)
		)
		(property "Manufacturer" "TDK"
			(at 65.365 364.465 0)
			(layer "B.Fab")
			(hide yes)
			(effects
				(font
					(size 1 1)
					(thickness 0.15)
				)
				(justify mirror)
			)
		)
		(property "Public" ""
			(at 65.365 364.465 0)
			(layer "B.Fab")
			(hide yes)
			(effects
				(font
					(size 1 1)
					(thickness 0.15)
				)
				(justify mirror)
			)
		)
		(property "Val" "1u"
			(at 65.365 364.465 0)
			(layer "B.Fab")
			(hide yes)
			(effects
				(font
					(size 1 1)
					(thickness 0.15)
				)
				(justify mirror)
			)
		)
		(property "Voltage" ""
			(at 65.365 364.465 0)
			(layer "B.Fab")
			(hide yes)
			(effects
				(font
					(size 1 1)
					(thickness 0.15)
				)
				(justify mirror)
			)
		)
		(sheetname "/USB/")
		(sheetfile "usb.kicad_sch")
		(attr smd)
		(fp_rect
			(start -0.925 0.47)
			(end 0.925 -0.47)
			(stroke
				(width 0.05)
				(type default)
			)
			(fill no)
			(layer "B.CrtYd")
		)
		(fp_line
			(start -0.494 0.25)
			(end 0.504 0.25)
			(stroke
				(width 0.15)
				(type solid)
			)
			(layer "B.Fab")
		)
		(fp_line
			(start 0.504 0.25)
			(end 0.504 -0.248)
			(stroke
				(width 0.15)
				(type solid)
			)
			(layer "B.Fab")
		)
		(fp_line
			(start -0.494 -0.248)
			(end -0.494 0.25)
			(stroke
				(width 0.15)
				(type solid)
			)
			(layer "B.Fab")
		)
		(fp_line
			(start 0.504 -0.248)
			(end -0.494 -0.248)
			(stroke
				(width 0.15)
				(type solid)
			)
			(layer "B.Fab")
		)
		(fp_text user "License: Apache-2.0"
			(at -0.939 -5.799 90)
			(layer "B.Fab")
			(effects
				(font
					(size 0.7 0.7)
					(thickness 0.15)
				)
				(justify left bottom mirror)
			)
		)
		(fp_text user "${REFERENCE}"
			(at -0.939 -4.599 90)
			(layer "B.Fab")
			(effects
				(font
					(size 0.7 0.7)
					(thickness 0.15)
				)
				(justify left bottom mirror)
			)
		)
		(fp_text user "Author: Antmicro"
			(at -0.939 -3.399 90)
			(layer "B.Fab")
			(effects
				(font
					(size 0.7 0.7)
					(thickness 0.15)
				)
				(justify left bottom mirror)
			)
		)
		(pad "1" smd roundrect
			(at -0.48 0 270)
			(size 0.59 0.64)
			(layers "B.Cu" "B.Mask" "B.Paste")
			(roundrect_rratio 0.25)
			(net 417 "GND")
			(pintype "passive")
		)
		(pad "2" smd roundrect
			(at 0.48 0 270)
			(size 0.59 0.64)
			(layers "B.Cu" "B.Mask" "B.Paste")
			(roundrect_rratio 0.25)
			(net 182 "Net-(U28-CRFILT)")
			(pintype "passive")
		)
	)
)
